(kicad_pcb
	(version 20260206)
	(generator "pcbnew")
	(generator_version "10.0")
	(general
		(thickness 1.6)
		(legacy_teardrops no)
	)
	(paper "A4")
	(title_block
		(title "Bryce Canyon_IOM_IOC_16318-2_OCP.brd")
		(comment 1 "Bryce Canyon / footprints 1248-1255 of 1605")
	)
	(layers
		(0 "F.Cu" signal "TOP")
		(4 "In1.Cu" signal "L2GND")
		(6 "In2.Cu" signal "L3")
		(8 "In3.Cu" signal "L4VCC")
		(10 "In4.Cu" signal "L5VCC")
		(12 "In5.Cu" signal "L6")
		(14 "In6.Cu" signal "L7GND")
		(2 "B.Cu" signal "BOTTOM")
		(9 "F.Adhes" user "F.Adhesive")
		(11 "B.Adhes" user "B.Adhesive")
		(13 "F.Paste" user "Package Geometry/Pastemask Top")
		(15 "B.Paste" user "Package Geometry/Pastemask Bottom")
		(5 "F.SilkS" user "Ref Des/Silkscreen Top")
		(7 "B.SilkS" user "Ref Des/Silkscreen Bottom")
		(1 "F.Mask" user "Board Geometry/Soldermask Top")
		(3 "B.Mask" user "Board Geometry/Soldermask Bottom")
		(17 "Dwgs.User" user "User.Drawings")
		(19 "Cmts.User" user "User.Comments")
		(21 "Eco1.User" user "User.Eco1")
		(23 "Eco2.User" user "User.Eco2")
		(25 "Edge.Cuts" user "Board Geometry/Outline")
		(27 "Margin" user)
		(31 "F.CrtYd" user "Package Geometry/Place Bound Top")
		(29 "B.CrtYd" user "Package Geometry/Place Bound Bottom")
		(35 "F.Fab" user "Ref Des/Assembly Top")
		(33 "B.Fab" user "Ref Des/Assembly Bottom")
	)
	(footprint ""
		(layer "B.Cu")
		(at 47.2313 -154.26944 -90)
		(property "Reference" "R368"
			(at 0 0 90)
			(layer "B.SilkS")
			(hide yes)
			(effects
				(font
					(size 1.27 1.27)
				)
				(justify mirror)
			)
		)
		(property "Value" "0R2J-2-GP"
			(at -0.064008 -3.993896 270)
			(unlocked yes)
			(layer "B.Fab")
			(hide yes)
			(effects
				(font
					(size 1.016 1.016)
					(thickness 0.1524)
				)
				(justify mirror)
			)
		)
		(property "Device Type" "R402H16"
			(at -0.064008 -5.517896 270)
			(unlocked yes)
			(layer "B.Fab")
			(hide yes)
			(effects
				(font
					(size 1.016 1.016)
					(thickness 0.1524)
				)
				(justify mirror)
			)
		)
		(duplicate_pad_numbers_are_jumpers no)
		(fp_line
			(start -0.508 -0.9398)
			(end 0.508 -0.9398)
			(stroke
				(width 0.1524)
				(type default)
			)
			(layer "B.SilkS")
		)
		(fp_line
			(start 0.508 -0.9398)
			(end 0.508 0.9398)
			(stroke
				(width 0.1524)
				(type default)
			)
			(layer "B.SilkS")
		)
		(fp_rect
			(start 0.508 0.9398)
			(end -0.508 -0.9398)
			(stroke
				(width 0)
				(type default)
			)
			(fill no)
			(layer "B.CrtYd")
		)
		(fp_rect
			(start 0.508 0.9398)
			(end -0.508 -0.9398)
			(stroke
				(width 0)
				(type default)
			)
			(fill no)
			(layer "B.Fab")
		)
		(pad "1" smd custom
			(at 0 -0.4445 90)
			(size 0.1397 0.1397)
			(layers "B.Cu" "B.Mask" "B.Paste")
			(net "P3V3_STBY")
			(options
				(clearance outline)
				(anchor circle)
			)
			(primitives
				(gr_poly
					(pts
						(arc
							(start -0.1778 0.2794)
							(mid -0.249642 0.249642)
							(end -0.2794 0.1778)
						)
						(arc
							(start -0.2794 -0.1778)
							(mid -0.249642 -0.249642)
							(end -0.1778 -0.2794)
						)
						(arc
							(start 0.1778 -0.2794)
							(mid 0.249642 -0.249642)
							(end 0.2794 -0.1778)
						)
						(arc
							(start 0.2794 0.1778)
							(mid 0.249642 0.249642)
							(end 0.1778 0.2794)
						)
					)
					(width 0)
					(fill yes)
				)
			)
		)
		(pad "2" smd custom
			(at 0 0.4445 90)
			(size 0.1397 0.1397)
			(layers "B.Cu" "B.Mask" "B.Paste")
			(net "DACAV33")
			(options
				(clearance outline)
				(anchor circle)
			)
			(primitives
				(gr_poly
					(pts
						(arc
							(start -0.1778 0.2794)
							(mid -0.249642 0.249642)
							(end -0.2794 0.1778)
						)
						(arc
							(start -0.2794 -0.1778)
							(mid -0.249642 -0.249642)
							(end -0.1778 -0.2794)
						)
						(arc
							(start 0.1778 -0.2794)
							(mid 0.249642 -0.249642)
							(end 0.2794 -0.1778)
						)
						(arc
							(start 0.2794 0.1778)
							(mid 0.249642 0.249642)
							(end 0.1778 0.2794)
						)
					)
					(width 0)
					(fill yes)
				)
			)
		)
	)
	(footprint ""
		(layer "B.Cu")
		(at 184.19318 -61.8998 90)
		(property "Reference" "C477"
			(at 0 0 90)
			(layer "B.SilkS")
			(hide yes)
			(effects
				(font
					(size 1.27 1.27)
				)
				(justify mirror)
			)
		)
		(property "Value" "SC1KP50V2KX-1GP"
			(at -1.1811 -2.7051 90)
			(unlocked yes)
			(layer "B.Fab")
			(hide yes)
			(effects
				(font
					(size 1.016 1.016)
					(thickness 0.1524)
				)
				(justify mirror)
			)
		)
		(property "Device Type" "C402H22"
			(at -1.1811 -4.2291 90)
			(unlocked yes)
			(layer "B.Fab")
			(hide yes)
			(effects
				(font
					(size 1.016 1.016)
					(thickness 0.1524)
				)
				(justify mirror)
			)
		)
		(duplicate_pad_numbers_are_jumpers no)
		(fp_rect
			(start 0.4318 0.9525)
			(end -0.4318 -0.9525)
			(stroke
				(width 0)
				(type default)
			)
			(fill no)
			(layer "B.CrtYd")
		)
		(fp_rect
			(start 0.4318 0.9525)
			(end -0.4318 -0.9525)
			(stroke
				(width 0)
				(type default)
			)
			(fill no)
			(layer "B.Fab")
		)
		(pad "1" smd custom
			(at 0 -0.4445 270)
			(size 0.1524 0.1524)
			(layers "B.Cu" "B.Mask" "B.Paste")
			(net "P1V8")
			(options
				(clearance outline)
				(anchor circle)
			)
			(primitives
				(gr_poly
					(pts
						(arc
							(start 0.3048 0.2032)
							(mid 0.275042 0.275042)
							(end 0.2032 0.3048)
						)
						(arc
							(start -0.2032 0.3048)
							(mid -0.275042 0.275042)
							(end -0.3048 0.2032)
						)
						(arc
							(start -0.3048 -0.2032)
							(mid -0.275042 -0.275042)
							(end -0.2032 -0.3048)
						)
						(arc
							(start 0.2032 -0.3048)
							(mid 0.275042 -0.275042)
							(end 0.3048 -0.2032)
						)
					)
					(width 0)
					(fill yes)
				)
			)
		)
		(pad "2" smd custom
			(at 0 0.4445 270)
			(size 0.1524 0.1524)
			(layers "B.Cu" "B.Mask" "B.Paste")
			(net "GND")
			(options
				(clearance outline)
				(anchor circle)
			)
			(primitives
				(gr_poly
					(pts
						(arc
							(start 0.3048 0.2032)
							(mid 0.275042 0.275042)
							(end 0.2032 0.3048)
						)
						(arc
							(start -0.2032 0.3048)
							(mid -0.275042 0.275042)
							(end -0.3048 0.2032)
						)
						(arc
							(start -0.3048 -0.2032)
							(mid -0.275042 -0.275042)
							(end -0.2032 -0.3048)
						)
						(arc
							(start 0.2032 -0.3048)
							(mid 0.275042 -0.275042)
							(end 0.3048 -0.2032)
						)
					)
					(width 0)
					(fill yes)
				)
			)
		)
	)
	(footprint ""
		(layer "B.Cu")
		(at 193.7004 -44.4246 -90)
		(property "Reference" "L13"
			(at 0 0 90)
			(layer "B.SilkS")
			(hide yes)
			(effects
				(font
					(size 1.27 1.27)
				)
				(justify mirror)
			)
		)
		(property "Value" "MPZ2012S601AT-GP"
			(at 0 -4.2418 270)
			(unlocked yes)
			(layer "B.Fab")
			(hide yes)
			(effects
				(font
					(size 1.016 1.016)
					(thickness 0.1524)
				)
				(justify mirror)
			)
		)
		(property "Device Type" "L805H42"
			(at 0 -5.7912 270)
			(unlocked yes)
			(layer "B.Fab")
			(hide yes)
			(effects
				(font
					(size 1.016 1.016)
					(thickness 0.1524)
				)
				(justify mirror)
			)
		)
		(duplicate_pad_numbers_are_jumpers no)
		(fp_line
			(start -0.889 1.7018)
			(end 0.889 1.7018)
			(stroke
				(width 0.1524)
				(type default)
			)
			(layer "B.SilkS")
		)
		(fp_line
			(start 0.889 1.7018)
			(end 0.889 -1.7018)
			(stroke
				(width 0.1524)
				(type default)
			)
			(layer "B.SilkS")
		)
		(fp_line
			(start -0.889 -1.7018)
			(end -0.889 1.7018)
			(stroke
				(width 0.1524)
				(type default)
			)
			(layer "B.SilkS")
		)
		(fp_line
			(start 0.889 -1.7018)
			(end -0.889 -1.7018)
			(stroke
				(width 0.1524)
				(type default)
			)
			(layer "B.SilkS")
		)
		(fp_rect
			(start 0.9652 1.778)
			(end -0.9652 -1.778)
			(stroke
				(width 0)
				(type default)
			)
			(fill no)
			(layer "B.CrtYd")
		)
		(fp_rect
			(start 0.9652 1.778)
			(end -0.9652 -1.778)
			(stroke
				(width 0)
				(type default)
			)
			(fill no)
			(layer "B.Fab")
		)
		(pad "1" smd rect
			(at 0 -0.9652 90)
			(size 1.397 1.143)
			(layers "B.Cu" "B.Mask" "B.Paste")
			(net "HM40ADC_VDDA")
		)
		(pad "2" smd rect
			(at 0 0.9652 90)
			(size 1.397 1.143)
			(layers "B.Cu" "B.Mask" "B.Paste")
			(net "P1V8")
		)
	)
	(footprint ""
		(layer "B.Cu")
		(at 200.3933 -57.8866 -90)
		(property "Reference" "C445"
			(at 0 0 90)
			(layer "B.SilkS")
			(hide yes)
			(effects
				(font
					(size 1.27 1.27)
				)
				(justify mirror)
			)
		)
		(property "Value" "SCD1U16V2KX-3GP"
			(at -1.1811 -2.7051 270)
			(unlocked yes)
			(layer "B.Fab")
			(hide yes)
			(effects
				(font
					(size 1.016 1.016)
					(thickness 0.1524)
				)
				(justify mirror)
			)
		)
		(property "Device Type" "C402H22"
			(at -1.1811 -4.2291 270)
			(unlocked yes)
			(layer "B.Fab")
			(hide yes)
			(effects
				(font
					(size 1.016 1.016)
					(thickness 0.1524)
				)
				(justify mirror)
			)
		)
		(duplicate_pad_numbers_are_jumpers no)
		(fp_rect
			(start 0.4318 0.9525)
			(end -0.4318 -0.9525)
			(stroke
				(width 0)
				(type default)
			)
			(fill no)
			(layer "B.CrtYd")
		)
		(fp_rect
			(start 0.4318 0.9525)
			(end -0.4318 -0.9525)
			(stroke
				(width 0)
				(type default)
			)
			(fill no)
			(layer "B.Fab")
		)
		(pad "1" smd custom
			(at 0 -0.4445 90)
			(size 0.1524 0.1524)
			(layers "B.Cu" "B.Mask" "B.Paste")
			(net "P1V8")
			(options
				(clearance outline)
				(anchor circle)
			)
			(primitives
				(gr_poly
					(pts
						(arc
							(start 0.3048 0.2032)
							(mid 0.275042 0.275042)
							(end 0.2032 0.3048)
						)
						(arc
							(start -0.2032 0.3048)
							(mid -0.275042 0.275042)
							(end -0.3048 0.2032)
						)
						(arc
							(start -0.3048 -0.2032)
							(mid -0.275042 -0.275042)
							(end -0.2032 -0.3048)
						)
						(arc
							(start 0.2032 -0.3048)
							(mid 0.275042 -0.275042)
							(end 0.3048 -0.2032)
						)
					)
					(width 0)
					(fill yes)
				)
			)
		)
		(pad "2" smd custom
			(at 0 0.4445 90)
			(size 0.1524 0.1524)
			(layers "B.Cu" "B.Mask" "B.Paste")
			(net "GND")
			(options
				(clearance outline)
				(anchor circle)
			)
			(primitives
				(gr_poly
					(pts
						(arc
							(start 0.3048 0.2032)
							(mid 0.275042 0.275042)
							(end 0.2032 0.3048)
						)
						(arc
							(start -0.2032 0.3048)
							(mid -0.275042 0.275042)
							(end -0.3048 0.2032)
						)
						(arc
							(start -0.3048 -0.2032)
							(mid -0.275042 -0.275042)
							(end -0.2032 -0.3048)
						)
						(arc
							(start 0.2032 -0.3048)
							(mid 0.275042 -0.275042)
							(end 0.3048 -0.2032)
						)
					)
					(width 0)
					(fill yes)
				)
			)
		)
	)
	(footprint ""
		(layer "B.Cu")
		(at 37.80536 -140.29309 180)
		(property "Reference" "C99"
			(at 0 0 0)
			(layer "B.SilkS")
			(hide yes)
			(effects
				(font
					(size 1.27 1.27)
				)
				(justify mirror)
			)
		)
		(property "Value" "SC1U16V3KX-5GP"
			(at 0 -2.8194 180)
			(unlocked yes)
			(layer "B.Fab")
			(hide yes)
			(effects
				(font
					(size 1.016 1.016)
					(thickness 0.1524)
				)
				(justify mirror)
			)
		)
		(property "Device Type" "C603H36"
			(at 0 -4.3434 180)
			(unlocked yes)
			(layer "B.Fab")
			(hide yes)
			(effects
				(font
					(size 1.016 1.016)
					(thickness 0.1524)
				)
				(justify mirror)
			)
		)
		(duplicate_pad_numbers_are_jumpers no)
		(fp_line
			(start -0.508 0)
			(end 0.508 0)
			(stroke
				(width 0.2032)
				(type default)
			)
			(layer "B.SilkS")
		)
		(fp_rect
			(start 0.5842 1.3335)
			(end -0.5842 -1.3335)
			(stroke
				(width 0)
				(type default)
			)
			(fill no)
			(layer "B.CrtYd")
		)
		(fp_rect
			(start 0.5842 1.3335)
			(end -0.5842 -1.3335)
			(stroke
				(width 0)
				(type default)
			)
			(fill no)
			(layer "B.Fab")
		)
		(pad "1" smd custom
			(at 0 -0.762)
			(size 0.2159 0.2159)
			(layers "B.Cu" "B.Mask" "B.Paste")
			(net "P3V3_STBY")
			(options
				(clearance outline)
				(anchor circle)
			)
			(primitives
				(gr_poly
					(pts
						(arc
							(start -0.3302 0.4318)
							(mid -0.402042 0.402042)
							(end -0.4318 0.3302)
						)
						(arc
							(start -0.4318 -0.3302)
							(mid -0.402042 -0.402042)
							(end -0.3302 -0.4318)
						)
						(arc
							(start 0.3302 -0.4318)
							(mid 0.402042 -0.402042)
							(end 0.4318 -0.3302)
						)
						(arc
							(start 0.4318 0.3302)
							(mid 0.402042 0.402042)
							(end 0.3302 0.4318)
						)
					)
					(width 0)
					(fill yes)
				)
			)
		)
		(pad "2" smd custom
			(at 0 0.762)
			(size 0.2159 0.2159)
			(layers "B.Cu" "B.Mask" "B.Paste")
			(net "GND")
			(options
				(clearance outline)
				(anchor circle)
			)
			(primitives
				(gr_poly
					(pts
						(arc
							(start -0.3302 0.4318)
							(mid -0.402042 0.402042)
							(end -0.4318 0.3302)
						)
						(arc
							(start -0.4318 -0.3302)
							(mid -0.402042 -0.402042)
							(end -0.3302 -0.4318)
						)
						(arc
							(start 0.3302 -0.4318)
							(mid 0.402042 -0.402042)
							(end 0.4318 -0.3302)
						)
						(arc
							(start 0.4318 0.3302)
							(mid 0.402042 0.402042)
							(end 0.3302 0.4318)
						)
					)
					(width 0)
					(fill yes)
				)
			)
		)
	)
	(footprint ""
		(layer "B.Cu")
		(at 195.7832 -76.454)
		(property "Reference" "C370"
			(at 0 0 0)
			(layer "B.SilkS")
			(hide yes)
			(effects
				(font
					(size 1.27 1.27)
				)
				(justify mirror)
			)
		)
		(property "Value" "SCD1U6D3V1KX-GP"
			(at 2.8321 -1.7399 0)
			(unlocked yes)
			(layer "B.Fab")
			(hide yes)
			(effects
				(font
					(size 1.016 1.016)
					(thickness 0.1524)
				)
				(justify mirror)
			)
		)
		(property "Device Type" "C0201H13"
			(at 2.8321 -3.2639 0)
			(unlocked yes)
			(layer "B.Fab")
			(hide yes)
			(effects
				(font
					(size 1.016 1.016)
					(thickness 0.1524)
				)
				(justify mirror)
			)
		)
		(duplicate_pad_numbers_are_jumpers no)
		(fp_rect
			(start 0.2794 0.6477)
			(end -0.2794 -0.6477)
			(stroke
				(width 0)
				(type default)
			)
			(fill no)
			(layer "B.CrtYd")
		)
		(fp_rect
			(start 0.2794 0.6477)
			(end -0.2794 -0.6477)
			(stroke
				(width 0)
				(type default)
			)
			(fill no)
			(layer "B.Fab")
		)
		(pad "1" smd custom
			(at 0 -0.2794 180)
			(size 0.0762 0.0762)
			(layers "B.Cu" "B.Mask" "B.Paste")
			(net "PCE_AVDD")
			(options
				(clearance outline)
				(anchor circle)
			)
			(primitives
				(gr_poly
					(pts
						(arc
							(start 0.1524 0.127)
							(mid 0.137521 0.162921)
							(end 0.1016 0.1778)
						)
						(arc
							(start -0.1016 0.1778)
							(mid -0.137521 0.162921)
							(end -0.1524 0.127)
						)
						(arc
							(start -0.1524 -0.127)
							(mid -0.137521 -0.162921)
							(end -0.1016 -0.1778)
						)
						(arc
							(start 0.1016 -0.1778)
							(mid 0.137521 -0.162921)
							(end 0.1524 -0.127)
						)
					)
					(width 0)
					(fill yes)
				)
			)
		)
		(pad "2" smd custom
			(at 0 0.2794 180)
			(size 0.0762 0.0762)
			(layers "B.Cu" "B.Mask" "B.Paste")
			(net "GND")
			(options
				(clearance outline)
				(anchor circle)
			)
			(primitives
				(gr_poly
					(pts
						(arc
							(start 0.1524 0.127)
							(mid 0.137521 0.162921)
							(end 0.1016 0.1778)
						)
						(arc
							(start -0.1016 0.1778)
							(mid -0.137521 0.162921)
							(end -0.1524 0.127)
						)
						(arc
							(start -0.1524 -0.127)
							(mid -0.137521 -0.162921)
							(end -0.1016 -0.1778)
						)
						(arc
							(start 0.1016 -0.1778)
							(mid 0.137521 -0.162921)
							(end 0.1524 -0.127)
						)
					)
					(width 0)
					(fill yes)
				)
			)
		)
	)
	(footprint ""
		(layer "B.Cu")
		(at 120.142 -6.477 90)
		(property "Reference" "C132"
			(at 0 0 90)
			(layer "B.SilkS")
			(hide yes)
			(effects
				(font
					(size 1.27 1.27)
				)
				(justify mirror)
			)
		)
		(property "Value" "SC22UF16V6KX-GP"
			(at 0 -6.8072 90)
			(unlocked yes)
			(layer "B.Fab")
			(hide yes)
			(effects
				(font
					(size 1.016 1.016)
					(thickness 0.1524)
				)
				(justify mirror)
			)
		)
		(property "Device Type" "C1206H75"
			(at 0 -8.7122 90)
			(unlocked yes)
			(layer "B.Fab")
			(hide yes)
			(effects
				(font
					(size 1.016 1.016)
					(thickness 0.1524)
				)
				(justify mirror)
			)
		)
		(duplicate_pad_numbers_are_jumpers no)
		(fp_line
			(start 1.016 -2.2352)
			(end 1.016 -0.8382)
			(stroke
				(width 0.1524)
				(type default)
			)
			(layer "B.SilkS")
		)
		(fp_line
			(start -1.016 -2.2352)
			(end 1.016 -2.2352)
			(stroke
				(width 0.1524)
				(type default)
			)
			(layer "B.SilkS")
		)
		(fp_line
			(start -1.016 -2.2352)
			(end -1.016 -0.8382)
			(stroke
				(width 0.1524)
				(type default)
			)
			(layer "B.SilkS")
		)
		(fp_line
			(start -1.016 0.8382)
			(end -1.016 2.2352)
			(stroke
				(width 0.1524)
				(type default)
			)
			(layer "B.SilkS")
		)
		(fp_line
			(start 1.016 2.2352)
			(end 1.016 0.8128)
			(stroke
				(width 0.1524)
				(type default)
			)
			(layer "B.SilkS")
		)
		(fp_line
			(start -1.016 2.2352)
			(end 1.016 2.2352)
			(stroke
				(width 0.1524)
				(type default)
			)
			(layer "B.SilkS")
		)
		(fp_rect
			(start 1.0922 2.3114)
			(end -1.0922 -2.3114)
			(stroke
				(width 0)
				(type default)
			)
			(fill no)
			(layer "B.CrtYd")
		)
		(fp_poly
			(pts
				(xy 1.0922 -2.3114) (xy -1.0922 -2.3114) (xy -1.0922 2.3114) (xy 1.0922 2.3114)
			)
			(stroke
				(width 0)
				(type default)
			)
			(fill no)
			(layer "B.Fab")
		)
		(pad "1" smd rect
			(at 0 -1.397 270)
			(size 1.651 1.27)
			(layers "B.Cu" "B.Mask" "B.Paste")
			(net "MB0_HS_ENABLE")
		)
		(pad "2" smd rect
			(at 0 1.397 270)
			(size 1.651 1.27)
			(layers "B.Cu" "B.Mask" "B.Paste")
			(net "GND")
		)
	)
	(footprint ""
		(layer "B.Cu")
		(at 122.3264 -15.9766 -90)
		(property "Reference" "R742"
			(at 0 0 90)
			(layer "B.SilkS")
			(hide yes)
			(effects
				(font
					(size 1.27 1.27)
				)
				(justify mirror)
			)
		)
		(property "Value" "10KR2F-2-GP"
			(at -0.064008 -3.993896 270)
			(unlocked yes)
			(layer "B.Fab")
			(hide yes)
			(effects
				(font
					(size 1.016 1.016)
					(thickness 0.1524)
				)
				(justify mirror)
			)
		)
		(property "Device Type" "R402H16"
			(at -0.064008 -5.517896 270)
			(unlocked yes)
			(layer "B.Fab")
			(hide yes)
			(effects
				(font
					(size 1.016 1.016)
					(thickness 0.1524)
				)
				(justify mirror)
			)
		)
		(duplicate_pad_numbers_are_jumpers no)
		(fp_line
			(start -0.508 -0.9398)
			(end 0.508 -0.9398)
			(stroke
				(width 0.1524)
				(type default)
			)
			(layer "B.SilkS")
		)
		(fp_line
			(start 0.508 -0.9398)
			(end 0.508 0.9398)
			(stroke
				(width 0.1524)
				(type default)
			)
			(layer "B.SilkS")
		)
		(fp_rect
			(start 0.508 0.9398)
			(end -0.508 -0.9398)
			(stroke
				(width 0)
				(type default)
			)
			(fill no)
			(layer "B.CrtYd")
		)
		(fp_rect
			(start 0.508 0.9398)
			(end -0.508 -0.9398)
			(stroke
				(width 0)
				(type default)
			)
			(fill no)
			(layer "B.Fab")
		)
		(pad "1" smd custom
			(at 0 -0.4445 90)
			(size 0.1397 0.1397)
			(layers "B.Cu" "B.Mask" "B.Paste")
			(net "P12V_IOM")
			(options
				(clearance outline)
				(anchor circle)
			)
			(primitives
				(gr_poly
					(pts
						(arc
							(start -0.1778 0.2794)
							(mid -0.249642 0.249642)
							(end -0.2794 0.1778)
						)
						(arc
							(start -0.2794 -0.1778)
							(mid -0.249642 -0.249642)
							(end -0.1778 -0.2794)
						)
						(arc
							(start 0.1778 -0.2794)
							(mid 0.249642 -0.249642)
							(end 0.2794 -0.1778)
						)
						(arc
							(start 0.2794 0.1778)
							(mid 0.249642 0.249642)
							(end 0.1778 0.2794)
						)
					)
					(width 0)
					(fill yes)
				)
			)
		)
		(pad "2" smd custom
			(at 0 0.4445 90)
			(size 0.1397 0.1397)
			(layers "B.Cu" "B.Mask" "B.Paste")
			(net "IOM_MATED_N")
			(options
				(clearance outline)
				(anchor circle)
			)
			(primitives
				(gr_poly
					(pts
						(arc
							(start -0.1778 0.2794)
							(mid -0.249642 0.249642)
							(end -0.2794 0.1778)
						)
						(arc
							(start -0.2794 -0.1778)
							(mid -0.249642 -0.249642)
							(end -0.1778 -0.2794)
						)
						(arc
							(start 0.1778 -0.2794)
							(mid 0.249642 -0.249642)
							(end 0.2794 -0.1778)
						)
						(arc
							(start 0.2794 0.1778)
							(mid 0.249642 0.249642)
							(end 0.1778 0.2794)
						)
					)
					(width 0)
					(fill yes)
				)
			)
		)
	)
)
